(kicad_pcb
	(version 20241229)
	(generator "pcbnew")
	(generator_version "9.0")
	(general
		(thickness 1.6642)
		(legacy_teardrops no)
	)
	(paper "A3")
	(title_block
		(title "PolarFire SoM")
		(date "2025-07-22")
		(rev "1.1.4")
		(company "Antmicro Ltd")
		(comment 1 "www.antmicro.com")
		(comment 9 "footprints 195-199 of 470")
	)
	(layers
		(0 "F.Cu" mixed)
		(4 "In1.Cu" power)
		(6 "In2.Cu" signal)
		(8 "In3.Cu" power)
		(10 "In4.Cu" signal)
		(12 "In5.Cu" power)
		(14 "In6.Cu" power)
		(16 "In7.Cu" signal)
		(18 "In8.Cu" power)
		(20 "In9.Cu" signal)
		(22 "In10.Cu" power)
		(24 "In11.Cu" signal)
		(26 "In12.Cu" signal)
		(2 "B.Cu" mixed)
		(9 "F.Adhes" user "F.Adhesive")
		(11 "B.Adhes" user "B.Adhesive")
		(13 "F.Paste" user)
		(15 "B.Paste" user)
		(5 "F.SilkS" user "F.Silkscreen")
		(7 "B.SilkS" user "B.Silkscreen")
		(1 "F.Mask" user)
		(3 "B.Mask" user)
		(17 "Dwgs.User" user "User.Drawings")
		(19 "Cmts.User" user "User.Comments")
		(21 "Eco1.User" user "User.Eco1")
		(23 "Eco2.User" user "User.Eco2")
		(25 "Edge.Cuts" user)
		(27 "Margin" user)
		(31 "F.CrtYd" user "F.Courtyard")
		(29 "B.CrtYd" user "B.Courtyard")
		(35 "F.Fab" user)
		(33 "B.Fab" user)
	)
	(footprint "antmicro-footprints:C_0603_1608Metric"
		(layer "B.Cu")
		(at 196.45 129.1)
		(descr "Capacitor SMD 0603")
		(tags "capacitor 0603")
		(property "Reference" "C262"
			(at -2.45 -0.8 0)
			(layer "B.SilkS")
			(effects
				(font
					(size 0.7 0.7)
					(thickness 0.15)
				)
				(justify right bottom mirror)
			)
		)
		(property "Value" "C_47u_0603"
			(at -1.42757 -1.770288 0)
			(layer "B.Fab")
			(hide yes)
			(effects
				(font
					(size 0.7 0.7)
					(thickness 0.15)
				)
				(justify right bottom mirror)
			)
		)
		(property "Datasheet" "https://www.murata.com/products/productdetail?partno=GRM188R60J476ME15%23"
			(at 0 0 0)
			(layer "F.Fab")
			(hide yes)
			(effects
				(font
					(size 1.27 1.27)
					(thickness 0.15)
				)
			)
		)
		(property "Description" "SMD Multilayer Ceramic Capacitor, 47 µF, 6.3 V, 0603 [1608 Metric], ± 20%, X5R, GRM Series"
			(at 0 0 0)
			(layer "F.Fab")
			(hide yes)
			(effects
				(font
					(size 1.27 1.27)
					(thickness 0.15)
				)
			)
		)
		(property "Author" "Antmicro"
			(at 0 0 0)
			(layer "B.Fab")
			(hide yes)
			(effects
				(font
					(size 1 1)
					(thickness 0.15)
				)
				(justify mirror)
			)
		)
		(property "Capacitance" "47u"
			(at 0 0 0)
			(layer "B.Fab")
			(hide yes)
			(effects
				(font
					(size 1 1)
					(thickness 0.15)
				)
				(justify mirror)
			)
		)
		(property "Dielectric" "X7R"
			(at 0 0 0)
			(layer "B.Fab")
			(hide yes)
			(effects
				(font
					(size 1 1)
					(thickness 0.15)
				)
				(justify mirror)
			)
		)
		(property "License" "Apache-2.0"
			(at 0 0 0)
			(layer "B.Fab")
			(hide yes)
			(effects
				(font
					(size 1 1)
					(thickness 0.15)
				)
				(justify mirror)
			)
		)
		(property "MPN" "GRM188R60J476ME15D"
			(at 0 0 0)
			(layer "B.Fab")
			(hide yes)
			(effects
				(font
					(size 1 1)
					(thickness 0.15)
				)
				(justify mirror)
			)
		)
		(property "Manufacturer" "Murata"
			(at 0 0 0)
			(layer "B.Fab")
			(hide yes)
			(effects
				(font
					(size 1 1)
					(thickness 0.15)
				)
				(justify mirror)
			)
		)
		(property "Public" ""
			(at 0 0 0)
			(layer "B.Fab")
			(hide yes)
			(effects
				(font
					(size 1 1)
					(thickness 0.15)
				)
				(justify mirror)
			)
		)
		(property "Val" "47u"
			(at 0 0 0)
			(layer "B.Fab")
			(hide yes)
			(effects
				(font
					(size 1 1)
					(thickness 0.15)
				)
				(justify mirror)
			)
		)
		(property "Voltage" "50V"
			(at 0 0 0)
			(layer "B.Fab")
			(hide yes)
			(effects
				(font
					(size 1 1)
					(thickness 0.15)
				)
				(justify mirror)
			)
		)
		(sheetname "/FPGA Supply/")
		(sheetfile "fpga-supply.kicad_sch")
		(attr smd)
		(fp_line
			(start -0.15 -0.4)
			(end 0.15 -0.4)
			(stroke
				(width 0.15)
				(type solid)
			)
			(layer "B.SilkS")
		)
		(fp_line
			(start -0.15 0.4)
			(end 0.15 0.4)
			(stroke
				(width 0.15)
				(type solid)
			)
			(layer "B.SilkS")
		)
		(fp_rect
			(start -1.25 0.65)
			(end 1.25 -0.65)
			(stroke
				(width 0.05)
				(type solid)
			)
			(fill no)
			(layer "B.CrtYd")
		)
		(fp_rect
			(start -0.8 0.4)
			(end 0.8 -0.4)
			(stroke
				(width 0.15)
				(type solid)
			)
			(fill no)
			(layer "B.Fab")
		)
		(fp_text user "Author: Antmicro"
			(at -1.682 -4.894 180)
			(layer "B.Fab")
			(effects
				(font
					(size 0.7 0.7)
					(thickness 0.15)
				)
				(justify left bottom mirror)
			)
		)
		(fp_text user "${REFERENCE}"
			(at -1.682 -3.895 180)
			(layer "B.Fab")
			(effects
				(font
					(size 0.7 0.7)
					(thickness 0.15)
				)
				(justify left bottom mirror)
			)
		)
		(fp_text user "License: Apache-2.0"
			(at -1.682 -5.895 180)
			(layer "B.Fab")
			(effects
				(font
					(size 0.7 0.7)
					(thickness 0.15)
				)
				(justify left bottom mirror)
			)
		)
		(pad "1" smd roundrect
			(at -0.7 0)
			(size 0.8 1)
			(layers "B.Cu" "B.Mask" "B.Paste")
			(roundrect_rratio 0.2)
			(net 417 "GND")
			(pintype "passive")
		)
		(pad "2" smd roundrect
			(at 0.7 0)
			(size 0.8 1)
			(layers "B.Cu" "B.Mask" "B.Paste")
			(roundrect_rratio 0.2)
			(net 49 "VDDAUX")
			(pintype "passive")
		)
	)
	(footprint "antmicro-footprints:TP_SMD_0.75mm"
		(layer "B.Cu")
		(at 203 123.1 180)
		(property "Reference" "TP25"
			(at 0.47 1.01 180)
			(layer "B.SilkS")
			(hide yes)
			(effects
				(font
					(size 0.65 0.65)
					(thickness 0.15)
				)
				(justify left bottom mirror)
			)
		)
		(property "Value" "TP_0.75mm_SMD"
			(at 0 -1.2 0)
			(layer "B.Fab")
			(hide yes)
			(effects
				(font
					(size 0.7 0.7)
					(thickness 0.15)
				)
				(justify left bottom mirror)
			)
		)
		(property "Description" "SMT test point"
			(at 0 0 0)
			(layer "B.Fab")
			(hide yes)
			(effects
				(font
					(size 1.27 1.27)
					(thickness 0.15)
				)
				(justify mirror)
			)
		)
		(property "MPN" ""
			(at 0 0 0)
			(unlocked yes)
			(layer "B.Fab")
			(hide yes)
			(effects
				(font
					(size 1 1)
					(thickness 0.15)
				)
				(justify mirror)
			)
		)
		(property "Manufacturer" ""
			(at 0 0 0)
			(unlocked yes)
			(layer "B.Fab")
			(hide yes)
			(effects
				(font
					(size 1 1)
					(thickness 0.15)
				)
				(justify mirror)
			)
		)
		(property "Author" "Antmicro"
			(at 0 0 0)
			(unlocked yes)
			(layer "B.Fab")
			(hide yes)
			(effects
				(font
					(size 1 1)
					(thickness 0.15)
				)
				(justify mirror)
			)
		)
		(property "License" "Apache-2.0"
			(at 0 0 0)
			(unlocked yes)
			(layer "B.Fab")
			(hide yes)
			(effects
				(font
					(size 1 1)
					(thickness 0.15)
				)
				(justify mirror)
			)
		)
		(property "Public" "False"
			(at 0 0 0)
			(unlocked yes)
			(layer "B.Fab")
			(hide yes)
			(effects
				(font
					(size 1 1)
					(thickness 0.15)
				)
				(justify mirror)
			)
		)
		(sheetname "/Supply/")
		(sheetfile "supply.kicad_sch")
		(attr exclude_from_pos_files exclude_from_bom)
		(fp_circle
			(center 0 0)
			(end 0.475 0)
			(stroke
				(width 0.05)
				(type default)
			)
			(fill no)
			(layer "B.CrtYd")
		)
		(fp_text user "License: Apache-2.0"
			(at -0.4 -5.101 0)
			(layer "B.Fab")
			(effects
				(font
					(size 0.7 0.7)
					(thickness 0.15)
				)
				(justify left bottom mirror)
			)
		)
		(fp_text user "Author: Antmicro"
			(at -0.4 -3.901 0)
			(layer "B.Fab")
			(effects
				(font
					(size 0.7 0.7)
					(thickness 0.15)
				)
				(justify left bottom mirror)
			)
		)
		(fp_text user "${REFERENCE}"
			(at -0.4 -2.7 0)
			(layer "B.Fab")
			(effects
				(font
					(size 0.7 0.7)
					(thickness 0.15)
				)
				(justify left bottom mirror)
			)
		)
		(pad "1" smd circle
			(at 0 0 180)
			(size 0.75 0.75)
			(layers "B.Cu" "B.Mask")
			(net 92 "/FPGA MSSIO/SUPPLY.SCL")
			(pinfunction "1")
			(pintype "passive")
		)
	)
	(footprint "antmicro-footprints:C_0402_1005Metric"
		(layer "B.Cu")
		(at 194.85 146.75 90)
		(descr "Capacitor SMD 0402")
		(tags "capacitor SMD 0402")
		(property "Reference" "C188"
			(at -3.65 0.1 90)
			(layer "B.SilkS")
			(effects
				(font
					(size 0.7 0.7)
					(thickness 0.15)
				)
				(justify right bottom mirror)
			)
		)
		(property "Value" "C_10u_10V_0402"
			(at -1.022927 -2.155213 90)
			(layer "B.Fab")
			(hide yes)
			(effects
				(font
					(size 0.7 0.7)
					(thickness 0.15)
				)
				(justify right bottom mirror)
			)
		)
		(property "Datasheet" "https://www.murata.com/products/productdetail?partno=GRM155R61A106ME11%23"
			(at 0 0 90)
			(layer "F.Fab")
			(hide yes)
			(effects
				(font
					(size 1.27 1.27)
					(thickness 0.15)
				)
			)
		)
		(property "Description" "Multilayer Ceramic Capacitors MLCC - SMD/SMT 10 uF 10 VDC 20% 0402 X5R"
			(at 0 0 90)
			(layer "F.Fab")
			(hide yes)
			(effects
				(font
					(size 1.27 1.27)
					(thickness 0.15)
				)
			)
		)
		(property "Author" "Antmicro"
			(at 341.6 -48.1 0)
			(layer "B.Fab")
			(hide yes)
			(effects
				(font
					(size 1 1)
					(thickness 0.15)
				)
				(justify mirror)
			)
		)
		(property "Dielectric" "X5R"
			(at 341.6 -48.1 0)
			(layer "B.Fab")
			(hide yes)
			(effects
				(font
					(size 1 1)
					(thickness 0.15)
				)
				(justify mirror)
			)
		)
		(property "License" "Apache-2.0"
			(at 341.6 -48.1 0)
			(layer "B.Fab")
			(hide yes)
			(effects
				(font
					(size 1 1)
					(thickness 0.15)
				)
				(justify mirror)
			)
		)
		(property "MPN" "GRM155R61A106ME11D"
			(at 341.6 -48.1 0)
			(layer "B.Fab")
			(hide yes)
			(effects
				(font
					(size 1 1)
					(thickness 0.15)
				)
				(justify mirror)
			)
		)
		(property "Manufacturer" "Murata"
			(at 341.6 -48.1 0)
			(layer "B.Fab")
			(hide yes)
			(effects
				(font
					(size 1 1)
					(thickness 0.15)
				)
				(justify mirror)
			)
		)
		(property "Public" ""
			(at 341.6 -48.1 0)
			(layer "B.Fab")
			(hide yes)
			(effects
				(font
					(size 1 1)
					(thickness 0.15)
				)
				(justify mirror)
			)
		)
		(property "Val" "10u"
			(at 341.6 -48.1 0)
			(layer "B.Fab")
			(hide yes)
			(effects
				(font
					(size 1 1)
					(thickness 0.15)
				)
				(justify mirror)
			)
		)
		(property "Voltage" "10V"
			(at 341.6 -48.1 0)
			(layer "B.Fab")
			(hide yes)
			(effects
				(font
					(size 1 1)
					(thickness 0.15)
				)
				(justify mirror)
			)
		)
		(sheetname "/HDMI/")
		(sheetfile "hdmi.kicad_sch")
		(attr smd)
		(fp_rect
			(start -0.925 0.47)
			(end 0.925 -0.47)
			(stroke
				(width 0.05)
				(type default)
			)
			(fill no)
			(layer "B.CrtYd")
		)
		(fp_line
			(start 0.504 -0.248)
			(end -0.494 -0.248)
			(stroke
				(width 0.15)
				(type solid)
			)
			(layer "B.Fab")
		)
		(fp_line
			(start -0.494 -0.248)
			(end -0.494 0.25)
			(stroke
				(width 0.15)
				(type solid)
			)
			(layer "B.Fab")
		)
		(fp_line
			(start 0.504 0.25)
			(end 0.504 -0.248)
			(stroke
				(width 0.15)
				(type solid)
			)
			(layer "B.Fab")
		)
		(fp_line
			(start -0.494 0.25)
			(end 0.504 0.25)
			(stroke
				(width 0.15)
				(type solid)
			)
			(layer "B.Fab")
		)
		(fp_text user "Author: Antmicro"
			(at -0.939 -3.399 270)
			(layer "B.Fab")
			(effects
				(font
					(size 0.7 0.7)
					(thickness 0.15)
				)
				(justify left bottom mirror)
			)
		)
		(fp_text user "${REFERENCE}"
			(at -0.939 -4.599 270)
			(layer "B.Fab")
			(effects
				(font
					(size 0.7 0.7)
					(thickness 0.15)
				)
				(justify left bottom mirror)
			)
		)
		(fp_text user "License: Apache-2.0"
			(at -0.939 -5.799 270)
			(layer "B.Fab")
			(effects
				(font
					(size 0.7 0.7)
					(thickness 0.15)
				)
				(justify left bottom mirror)
			)
		)
		(pad "1" smd roundrect
			(at -0.48 0 90)
			(size 0.59 0.64)
			(layers "B.Cu" "B.Mask" "B.Paste")
			(roundrect_rratio 0.25)
			(net 417 "GND")
			(pintype "passive")
		)
		(pad "2" smd roundrect
			(at 0.48 0 90)
			(size 0.59 0.64)
			(layers "B.Cu" "B.Mask" "B.Paste")
			(roundrect_rratio 0.25)
			(net 553 "/HDMI/HDMI_3V3")
			(pintype "passive")
		)
	)
	(footprint "antmicro-footprints:C_0402_1005Metric"
		(layer "B.Cu")
		(at 203.21 126.71 180)
		(descr "Capacitor SMD 0402")
		(tags "capacitor SMD 0402")
		(property "Reference" "C15"
			(at -3.04 -0.865 0)
			(layer "B.SilkS")
			(effects
				(font
					(size 0.7 0.7)
					(thickness 0.15)
				)
				(justify left bottom mirror)
			)
		)
		(property "Value" "C_100n_0402"
			(at -1.022927 -2.155213 0)
			(layer "B.Fab")
			(hide yes)
			(effects
				(font
					(size 0.7 0.7)
					(thickness 0.15)
				)
				(justify left bottom mirror)
			)
		)
		(property "Datasheet" "https://www.murata.com/products/productdetail?partno=GRM155R61H104KE14%23"
			(at 0 0 180)
			(layer "F.Fab")
			(hide yes)
			(effects
				(font
					(size 1.27 1.27)
					(thickness 0.15)
				)
			)
		)
		(property "Description" "SMD Multilayer Ceramic Capacitor, 0.1 µF, 50 V, 0402 [1005 Metric], ± 10%, X5R, GRM Series"
			(at 0 0 180)
			(layer "F.Fab")
			(hide yes)
			(effects
				(font
					(size 1.27 1.27)
					(thickness 0.15)
				)
			)
		)
		(property "Author" "Antmicro"
			(at 406.42 253.42 0)
			(layer "B.Fab")
			(hide yes)
			(effects
				(font
					(size 1 1)
					(thickness 0.15)
				)
				(justify mirror)
			)
		)
		(property "Dielectric" "X5R"
			(at 406.42 253.42 0)
			(layer "B.Fab")
			(hide yes)
			(effects
				(font
					(size 1 1)
					(thickness 0.15)
				)
				(justify mirror)
			)
		)
		(property "License" "Apache-2.0"
			(at 406.42 253.42 0)
			(layer "B.Fab")
			(hide yes)
			(effects
				(font
					(size 1 1)
					(thickness 0.15)
				)
				(justify mirror)
			)
		)
		(property "MPN" "GRM155R61H104KE14D"
			(at 406.42 253.42 0)
			(layer "B.Fab")
			(hide yes)
			(effects
				(font
					(size 1 1)
					(thickness 0.15)
				)
				(justify mirror)
			)
		)
		(property "Manufacturer" "Murata"
			(at 406.42 253.42 0)
			(layer "B.Fab")
			(hide yes)
			(effects
				(font
					(size 1 1)
					(thickness 0.15)
				)
				(justify mirror)
			)
		)
		(property "Public" ""
			(at 406.42 253.42 0)
			(layer "B.Fab")
			(hide yes)
			(effects
				(font
					(size 1 1)
					(thickness 0.15)
				)
				(justify mirror)
			)
		)
		(property "Val" "100n"
			(at 406.42 253.42 0)
			(layer "B.Fab")
			(hide yes)
			(effects
				(font
					(size 1 1)
					(thickness 0.15)
				)
				(justify mirror)
			)
		)
		(property "Voltage" "50V"
			(at 406.42 253.42 0)
			(layer "B.Fab")
			(hide yes)
			(effects
				(font
					(size 1 1)
					(thickness 0.15)
				)
				(justify mirror)
			)
		)
		(sheetname "/FPGA Supply/")
		(sheetfile "fpga-supply.kicad_sch")
		(attr smd)
		(fp_rect
			(start -0.925 0.47)
			(end 0.925 -0.47)
			(stroke
				(width 0.05)
				(type default)
			)
			(fill no)
			(layer "B.CrtYd")
		)
		(fp_line
			(start 0.504 0.25)
			(end 0.504 -0.248)
			(stroke
				(width 0.15)
				(type solid)
			)
			(layer "B.Fab")
		)
		(fp_line
			(start 0.504 -0.248)
			(end -0.494 -0.248)
			(stroke
				(width 0.15)
				(type solid)
			)
			(layer "B.Fab")
		)
		(fp_line
			(start -0.494 0.25)
			(end 0.504 0.25)
			(stroke
				(width 0.15)
				(type solid)
			)
			(layer "B.Fab")
		)
		(fp_line
			(start -0.494 -0.248)
			(end -0.494 0.25)
			(stroke
				(width 0.15)
				(type solid)
			)
			(layer "B.Fab")
		)
		(fp_text user "${REFERENCE}"
			(at -0.939 -4.599 0)
			(layer "B.Fab")
			(effects
				(font
					(size 0.7 0.7)
					(thickness 0.15)
				)
				(justify left bottom mirror)
			)
		)
		(fp_text user "Author: Antmicro"
			(at -0.939 -3.399 0)
			(layer "B.Fab")
			(effects
				(font
					(size 0.7 0.7)
					(thickness 0.15)
				)
				(justify left bottom mirror)
			)
		)
		(fp_text user "License: Apache-2.0"
			(at -0.939 -5.799 0)
			(layer "B.Fab")
			(effects
				(font
					(size 0.7 0.7)
					(thickness 0.15)
				)
				(justify left bottom mirror)
			)
		)
		(pad "1" smd roundrect
			(at -0.48 0 180)
			(size 0.59 0.64)
			(layers "B.Cu" "B.Mask" "B.Paste")
			(roundrect_rratio 0.25)
			(net 417 "GND")
			(pintype "passive")
		)
		(pad "2" smd roundrect
			(at 0.48 0 180)
			(size 0.59 0.64)
			(layers "B.Cu" "B.Mask" "B.Paste")
			(roundrect_rratio 0.25)
			(net 649 "VDD")
			(pintype "passive")
		)
	)
	(footprint "antmicro-footprints:FB_0603_1608Metric"
		(layer "B.Cu")
		(at 213.1 142.95 180)
		(property "Reference" "FB1"
			(at 1.25 -0.65 0)
			(layer "B.SilkS")
			(effects
				(font
					(size 0.7 0.7)
					(thickness 0.15)
				)
				(justify left bottom mirror)
			)
		)
		(property "Value" "FB_470Z_1A_Murata-BLM18PG_0603"
			(at 0 -1.5 0)
			(layer "B.Fab")
			(hide yes)
			(effects
				(font
					(size 0.7 0.7)
					(thickness 0.15)
				)
				(justify left bottom mirror)
			)
		)
		(property "Datasheet" "https://www.murata.com/en-us/products/productdata/8796738650142/ENFA0003.pdf"
			(at 0 0 180)
			(layer "F.Fab")
			(hide yes)
			(effects
				(font
					(size 1.27 1.27)
					(thickness 0.15)
				)
			)
		)
		(property "Description" "Ferrite Bead, 0603 [1608 Metric], 470 ohm, 1 A, BLM18P, 0.2 ohm, ± 25%, DC power line"
			(at 0 0 180)
			(layer "F.Fab")
			(hide yes)
			(effects
				(font
					(size 1.27 1.27)
					(thickness 0.15)
				)
			)
		)
		(property "Author" "Antmicro"
			(at 426.2 285.9 0)
			(layer "B.Fab")
			(hide yes)
			(effects
				(font
					(size 1 1)
					(thickness 0.15)
				)
				(justify mirror)
			)
		)
		(property "Current" ""
			(at 426.2 285.9 0)
			(layer "B.Fab")
			(hide yes)
			(effects
				(font
					(size 1 1)
					(thickness 0.15)
				)
				(justify mirror)
			)
		)
		(property "License" "Apache-2.0"
			(at 426.2 285.9 0)
			(layer "B.Fab")
			(hide yes)
			(effects
				(font
					(size 1 1)
					(thickness 0.15)
				)
				(justify mirror)
			)
		)
		(property "MPN" "BLM18PG471SN1D"
			(at 426.2 285.9 0)
			(layer "B.Fab")
			(hide yes)
			(effects
				(font
					(size 1 1)
					(thickness 0.15)
				)
				(justify mirror)
			)
		)
		(property "Manufacturer" "Murata"
			(at 426.2 285.9 0)
			(layer "B.Fab")
			(hide yes)
			(effects
				(font
					(size 1 1)
					(thickness 0.15)
				)
				(justify mirror)
			)
		)
		(property "Public" ""
			(at 426.2 285.9 0)
			(layer "B.Fab")
			(hide yes)
			(effects
				(font
					(size 1 1)
					(thickness 0.15)
				)
				(justify mirror)
			)
		)
		(property "Val" "470Z/1A"
			(at 426.2 285.9 0)
			(layer "B.Fab")
			(hide yes)
			(effects
				(font
					(size 1 1)
					(thickness 0.15)
				)
				(justify mirror)
			)
		)
		(sheetname "/USB/")
		(sheetfile "usb.kicad_sch")
		(attr smd)
		(fp_line
			(start -0.15 0.4)
			(end 0.15 0.4)
			(stroke
				(width 0.15)
				(type solid)
			)
			(layer "B.SilkS")
		)
		(fp_line
			(start -0.15 -0.4)
			(end 0.15 -0.4)
			(stroke
				(width 0.15)
				(type solid)
			)
			(layer "B.SilkS")
		)
		(fp_rect
			(start -1.25 0.65)
			(end 1.25 -0.65)
			(stroke
				(width 0.05)
				(type solid)
			)
			(fill no)
			(layer "B.CrtYd")
		)
		(fp_line
			(start 0.8 0.408)
			(end 0.8 -0.406)
			(stroke
				(width 0.15)
				(type solid)
			)
			(layer "B.Fab")
		)
		(fp_line
			(start 0.8 0.408)
			(end -0.803 0.408)
			(stroke
				(width 0.15)
				(type solid)
			)
			(layer "B.Fab")
		)
		(fp_line
			(start 0.8 -0.406)
			(end -0.803 -0.406)
			(stroke
				(width 0.15)
				(type solid)
			)
			(layer "B.Fab")
		)
		(fp_line
			(start -0.803 -0.406)
			(end -0.803 0.408)
			(stroke
				(width 0.15)
				(type solid)
			)
			(layer "B.Fab")
		)
		(fp_text user "${REFERENCE}"
			(at -1.653 -4.6 0)
			(layer "B.Fab")
			(effects
				(font
					(size 0.7 0.7)
					(thickness 0.15)
				)
				(justify left bottom mirror)
			)
		)
		(fp_text user "Author: Antmicro"
			(at -1.653 -3.162 0)
			(layer "B.Fab")
			(effects
				(font
					(size 0.7 0.7)
					(thickness 0.15)
				)
				(justify left bottom mirror)
			)
		)
		(fp_text user "License: Apache-2.0"
			(at -1.653 -5.9 0)
			(layer "B.Fab")
			(effects
				(font
					(size 0.7 0.7)
					(thickness 0.15)
				)
				(justify left bottom mirror)
			)
		)
		(pad "1" smd roundrect
			(at -0.7 0 180)
			(size 0.8 1)
			(layers "B.Cu" "B.Mask" "B.Paste")
			(roundrect_rratio 0.2)
			(net 152 "/USB/VDDIO")
			(pintype "passive")
		)
		(pad "2" smd roundrect
			(at 0.7 0 180)
			(size 0.8 1)
			(layers "B.Cu" "B.Mask" "B.Paste")
			(roundrect_rratio 0.2)
			(net 649 "VDD")
			(pintype "passive")
		)
	)
)
